(kicad_pcb
	(version 20260206)
	(generator "pcbnew")
	(generator_version "10.0")
	(general
		(thickness 1.6)
		(legacy_teardrops no)
	)
	(paper "A4")
	(title_block
		(title "03242023_DA0F0TMBIJ0_F0T_Motherboard_J_brd_V01_OCP.brd")
		(comment 1 "Grand Teton / footprint 3039 of 6105 (U2), pads 3567-3678 of 4677")
	)
	(layers
		(0 "F.Cu" signal "TOP")
		(4 "In1.Cu" signal "GND")
		(6 "In2.Cu" signal "IN1")
		(8 "In3.Cu" signal "GND1")
		(10 "In4.Cu" signal "IN2")
		(12 "In5.Cu" signal "GND2")
		(14 "In6.Cu" signal "IN3")
		(16 "In7.Cu" signal "GND3")
		(18 "In8.Cu" signal "VCC")
		(20 "In9.Cu" signal "VCC1")
		(22 "In10.Cu" signal "GND4")
		(24 "In11.Cu" signal "IN4")
		(26 "In12.Cu" signal "GND5")
		(28 "In13.Cu" signal "IN5")
		(30 "In14.Cu" signal "GND6")
		(32 "In15.Cu" signal "IN6")
		(34 "In16.Cu" signal "GND7")
		(2 "B.Cu" signal "BOTTOM")
		(9 "F.Adhes" user "F.Adhesive")
		(11 "B.Adhes" user "B.Adhesive")
		(13 "F.Paste" user "Package Geometry/Pastemask Top")
		(15 "B.Paste" user "Package Geometry/Pastemask Bottom")
		(5 "F.SilkS" user "Ref Des/Silkscreen Top")
		(7 "B.SilkS" user "Ref Des/Silkscreen Bottom")
		(1 "F.Mask" user "Board Geometry/Soldermask Top")
		(3 "B.Mask" user "Board Geometry/Soldermask Bottom")
		(17 "Dwgs.User" user "User.Drawings")
		(19 "Cmts.User" user "User.Comments")
		(21 "Eco1.User" user "User.Eco1")
		(23 "Eco2.User" user "User.Eco2")
		(25 "Edge.Cuts" user "Board Geometry/Outline")
		(27 "Margin" user)
		(31 "F.CrtYd" user "Package Geometry/Place Bound Top")
		(29 "B.CrtYd" user "Package Geometry/Place Bound Bottom")
		(35 "F.Fab" user "Ref Des/Assembly Top")
		(33 "B.Fab" user "Ref Des/Assembly Bottom")
	)
	(footprint ""
		(layer "F.Cu")
		(at 359.870248 -251.76988 90)
		(property "Reference" "U2"
			(at -74.416158 -44.488608 0)
			(unlocked yes)
			(layer "F.SilkS")
			(effects
				(font
					(size 1.6002 1.1938)
					(thickness 0.1524)
				)
				(justify left)
			)
		)
		(property "Value" ""
			(at 0 0 90)
			(layer "F.Fab")
			(effects
				(font
					(size 1.27 1.27)
				)
			)
		)
		(duplicate_pad_numbers_are_jumpers no)
		(pad "EF22" smd circle
			(at -20.333462 22.265386 270)
			(size 0.4318 0.4318)
			(layers "F.Cu" "F.Mask" "F.Paste")
			(net "GND")
		)
		(pad "EF24" smd circle
			(at -18.705576 22.265386 270)
			(size 0.4318 0.4318)
			(layers "F.Cu" "F.Mask" "F.Paste")
			(net "GND")
		)
		(pad "EF26" smd circle
			(at -17.07769 22.265386 270)
			(size 0.4318 0.4318)
			(layers "F.Cu" "F.Mask" "F.Paste")
			(net "GND")
		)
		(pad "EF28" smd circle
			(at -15.450058 22.265386 270)
			(size 0.4318 0.4318)
			(layers "F.Cu" "F.Mask" "F.Paste")
			(net "GND")
		)
		(pad "EF30" smd circle
			(at -13.822426 22.265386 270)
			(size 0.4318 0.4318)
			(layers "F.Cu" "F.Mask" "F.Paste")
			(net "GND")
		)
		(pad "EF32" smd circle
			(at -12.19454 22.265386 270)
			(size 0.4318 0.4318)
			(layers "F.Cu" "F.Mask" "F.Paste")
			(net "GND")
		)
		(pad "EF34" smd circle
			(at -10.566654 22.265386 270)
			(size 0.4318 0.4318)
			(layers "F.Cu" "F.Mask" "F.Paste")
			(net "GND")
		)
		(pad "EF36" smd circle
			(at -8.939022 22.265386 270)
			(size 0.4318 0.4318)
			(layers "F.Cu" "F.Mask" "F.Paste")
			(net "GND")
		)
		(pad "EF38" smd circle
			(at -7.311136 22.265386 270)
			(size 0.4318 0.4318)
			(layers "F.Cu" "F.Mask" "F.Paste")
			(net "GND")
		)
		(pad "EF40" smd circle
			(at -5.68325 22.265386 270)
			(size 0.4318 0.4318)
			(layers "F.Cu" "F.Mask" "F.Paste")
			(net "GND")
		)
		(pad "EF42" smd circle
			(at -4.055618 22.265386 270)
			(size 0.4318 0.4318)
			(layers "F.Cu" "F.Mask" "F.Paste")
			(net "GND")
		)
		(pad "EF44" smd circle
			(at -2.427732 22.265386 270)
			(size 0.4318 0.4318)
			(layers "F.Cu" "F.Mask" "F.Paste")
			(net "GND")
		)
		(pad "EF47" smd circle
			(at 1.613916 22.375114 270)
			(size 0.4318 0.4318)
			(layers "F.Cu" "F.Mask" "F.Paste")
			(net "GND")
		)
		(pad "EF49" smd circle
			(at 3.241802 22.375114 270)
			(size 0.4318 0.4318)
			(layers "F.Cu" "F.Mask" "F.Paste")
			(net "GND")
		)
		(pad "EF51" smd circle
			(at 4.869434 22.375114 270)
			(size 0.4318 0.4318)
			(layers "F.Cu" "F.Mask" "F.Paste")
			(net "GND")
		)
		(pad "EF53" smd circle
			(at 6.49732 22.375114 270)
			(size 0.4318 0.4318)
			(layers "F.Cu" "F.Mask" "F.Paste")
			(net "GND")
		)
		(pad "EF55" smd circle
			(at 8.124952 22.375114 270)
			(size 0.4318 0.4318)
			(layers "F.Cu" "F.Mask" "F.Paste")
			(net "GND")
		)
		(pad "EF57" smd circle
			(at 9.752838 22.375114 270)
			(size 0.4318 0.4318)
			(layers "F.Cu" "F.Mask" "F.Paste")
			(net "GND")
		)
		(pad "EF59" smd circle
			(at 11.380724 22.375114 270)
			(size 0.4318 0.4318)
			(layers "F.Cu" "F.Mask" "F.Paste")
			(net "GND")
		)
		(pad "EF61" smd circle
			(at 13.008356 22.375114 270)
			(size 0.4318 0.4318)
			(layers "F.Cu" "F.Mask" "F.Paste")
			(net "GND")
		)
		(pad "EF63" smd circle
			(at 14.635988 22.375114 270)
			(size 0.4318 0.4318)
			(layers "F.Cu" "F.Mask" "F.Paste")
			(net "GND")
		)
		(pad "EF65" smd circle
			(at 16.263874 22.375114 270)
			(size 0.4318 0.4318)
			(layers "F.Cu" "F.Mask" "F.Paste")
			(net "GND")
		)
		(pad "EF67" smd circle
			(at 17.89176 22.375114 270)
			(size 0.4318 0.4318)
			(layers "F.Cu" "F.Mask" "F.Paste")
			(net "GND")
		)
		(pad "EF69" smd circle
			(at 19.519392 22.375114 270)
			(size 0.4318 0.4318)
			(layers "F.Cu" "F.Mask" "F.Paste")
			(net "GND")
		)
		(pad "EF71" smd circle
			(at 21.147278 22.375114 270)
			(size 0.4318 0.4318)
			(layers "F.Cu" "F.Mask" "F.Paste")
			(net "GND")
		)
		(pad "EF73" smd circle
			(at 22.77491 22.375114 270)
			(size 0.4318 0.4318)
			(layers "F.Cu" "F.Mask" "F.Paste")
			(net "GND")
		)
		(pad "EF75" smd circle
			(at 24.402796 22.375114 270)
			(size 0.4318 0.4318)
			(layers "F.Cu" "F.Mask" "F.Paste")
			(net "GND")
		)
		(pad "EF77" smd circle
			(at 26.030682 22.375114 270)
			(size 0.4318 0.4318)
			(layers "F.Cu" "F.Mask" "F.Paste")
			(net "GND")
		)
		(pad "EF79" smd circle
			(at 27.658314 22.375114 270)
			(size 0.4318 0.4318)
			(layers "F.Cu" "F.Mask" "F.Paste")
			(net "PVCCFA_EHV_FIVRA_CPU0")
		)
		(pad "EF81" smd circle
			(at 29.2862 22.375114 270)
			(size 0.4318 0.4318)
			(layers "F.Cu" "F.Mask" "F.Paste")
			(net "GND")
		)
		(pad "EF83" smd circle
			(at 30.914086 22.375114 270)
			(size 0.4318 0.4318)
			(layers "F.Cu" "F.Mask" "F.Paste")
			(net "GND")
		)
		(pad "EF85" smd circle
			(at 32.541718 22.375114 270)
			(size 0.4318 0.4318)
			(layers "F.Cu" "F.Mask" "F.Paste")
			(net "GND")
		)
		(pad "EF87" smd circle
			(at 34.169604 22.375114 270)
			(size 0.4318 0.4318)
			(layers "F.Cu" "F.Mask" "F.Paste")
			(net "GND")
		)
		(pad "EF89" smd circle
			(at 35.797236 22.375114 270)
			(size 0.4318 0.4318)
			(layers "F.Cu" "F.Mask" "F.Paste")
			(net "GND")
		)
		(pad "EG3" smd circle
			(at -35.797236 22.735286 270)
			(size 0.4318 0.4318)
			(layers "F.Cu" "F.Mask" "F.Paste")
			(net "UPI_CPU1_CPU0_P0P1_DP<1>")
		)
		(pad "EG5" smd circle
			(at -34.169604 22.735286 270)
			(size 0.4318 0.4318)
			(layers "F.Cu" "F.Mask" "F.Paste")
			(net "GND")
		)
		(pad "EG7" smd circle
			(at -32.541718 22.735286 270)
			(size 0.4318 0.4318)
			(layers "F.Cu" "F.Mask" "F.Paste")
			(net "GND")
		)
		(pad "EG9" smd circle
			(at -30.914086 22.735286 270)
			(size 0.4318 0.4318)
			(layers "F.Cu" "F.Mask" "F.Paste")
			(net "GND")
		)
		(pad "EG11" smd circle
			(at -29.2862 22.735286 270)
			(size 0.4318 0.4318)
			(layers "F.Cu" "F.Mask" "F.Paste")
			(net "P5E_CPU0_PE2_RX_DP<15>")
		)
		(pad "EG13" smd circle
			(at -27.658314 22.735286 270)
			(size 0.4318 0.4318)
			(layers "F.Cu" "F.Mask" "F.Paste")
			(net "GND")
		)
		(pad "EG15" smd circle
			(at -26.030682 22.735286 270)
			(size 0.4318 0.4318)
			(layers "F.Cu" "F.Mask" "F.Paste")
			(net "P5E_CPU0_PE2_TX_DP<15>")
		)
		(pad "EG17" smd circle
			(at -24.402796 22.735286 270)
			(size 0.4318 0.4318)
			(layers "F.Cu" "F.Mask" "F.Paste")
			(net "NC_CPU0_HBM0_VIEWDIG1")
		)
		(pad "EG19" smd circle
			(at -22.77491 22.735286 270)
			(size 0.4318 0.4318)
			(layers "F.Cu" "F.Mask" "F.Paste")
			(net "M_F_CPU0_SB_DQ<15>")
		)
		(pad "EG21" smd circle
			(at -21.147278 22.735286 270)
			(size 0.4318 0.4318)
			(layers "F.Cu" "F.Mask" "F.Paste")
			(net "M_F_CPU0_SB_DQS_DP<6>")
		)
		(pad "EG23" smd circle
			(at -19.519392 22.735286 270)
			(size 0.4318 0.4318)
			(layers "F.Cu" "F.Mask" "F.Paste")
			(net "M_F_CPU0_SB_DQ<10>")
		)
		(pad "EG25" smd circle
			(at -17.89176 22.735286 270)
			(size 0.4318 0.4318)
			(layers "F.Cu" "F.Mask" "F.Paste")
			(net "M_E_CPU0_SB_DQ<7>")
		)
		(pad "EG27" smd circle
			(at -16.263874 22.735286 270)
			(size 0.4318 0.4318)
			(layers "F.Cu" "F.Mask" "F.Paste")
			(net "M_E_CPU0_SB_DQS_DP<5>")
		)
		(pad "EG29" smd circle
			(at -14.635988 22.735286 270)
			(size 0.4318 0.4318)
			(layers "F.Cu" "F.Mask" "F.Paste")
			(net "M_E_CPU0_SB_DQ<2>")
		)
		(pad "EG31" smd circle
			(at -13.008356 22.735286 270)
			(size 0.4318 0.4318)
			(layers "F.Cu" "F.Mask" "F.Paste")
			(net "M_F_CPU0_SB_CB<3>")
		)
		(pad "EG33" smd circle
			(at -11.380724 22.735286 270)
			(size 0.4318 0.4318)
			(layers "F.Cu" "F.Mask" "F.Paste")
			(net "M_F_CPU0_SB_DQS_DP<4>")
		)
		(pad "EG35" smd circle
			(at -9.752838 22.735286 270)
			(size 0.4318 0.4318)
			(layers "F.Cu" "F.Mask" "F.Paste")
			(net "M_F_CPU0_SB_CB<6>")
		)
		(pad "EG37" smd circle
			(at -8.124952 22.735286 270)
			(size 0.4318 0.4318)
			(layers "F.Cu" "F.Mask" "F.Paste")
			(net "M_F_CPU0_SB_CS_N<1>")
		)
		(pad "EG39" smd circle
			(at -6.49732 22.735286 270)
			(size 0.4318 0.4318)
			(layers "F.Cu" "F.Mask" "F.Paste")
			(net "GND")
		)
		(pad "EG41" smd circle
			(at -4.869434 22.735286 270)
			(size 0.4318 0.4318)
			(layers "F.Cu" "F.Mask" "F.Paste")
			(net "M_F_CPU0_SB_CA<3>")
		)
		(pad "EG43" smd circle
			(at -3.241802 22.735286 270)
			(size 0.4318 0.4318)
			(layers "F.Cu" "F.Mask" "F.Paste")
			(net "M_E_CPU0_SB_CA<0>")
		)
		(pad "EG45" smd circle
			(at -1.613916 22.735286 270)
			(size 0.4318 0.4318)
			(layers "F.Cu" "F.Mask" "F.Paste")
			(net "M_E_CPU0_CLK_DP<0>")
		)
		(pad "EG48" smd circle
			(at 2.427732 22.845268 270)
			(size 0.4318 0.4318)
			(layers "F.Cu" "F.Mask" "F.Paste")
			(net "M_H_CPU0_SA_RSP<0>")
		)
		(pad "EG50" smd circle
			(at 4.055618 22.845268 270)
			(size 0.4318 0.4318)
			(layers "F.Cu" "F.Mask" "F.Paste")
			(net "M_F_CPU0_SA_CA<5>")
		)
		(pad "EG52" smd circle
			(at 5.68325 22.845268 270)
			(size 0.4318 0.4318)
			(layers "F.Cu" "F.Mask" "F.Paste")
			(net "GND")
		)
		(pad "EG54" smd circle
			(at 7.311136 22.845268 270)
			(size 0.4318 0.4318)
			(layers "F.Cu" "F.Mask" "F.Paste")
			(net "M_F_CPU0_SA_CS_N<0>")
		)
		(pad "EG56" smd circle
			(at 8.939022 22.845268 270)
			(size 0.4318 0.4318)
			(layers "F.Cu" "F.Mask" "F.Paste")
			(net "M_F_CPU0_SA_CB<7>")
		)
		(pad "EG58" smd circle
			(at 10.566654 22.845268 270)
			(size 0.4318 0.4318)
			(layers "F.Cu" "F.Mask" "F.Paste")
			(net "M_F_CPU0_SA_DQS_DP<9>")
		)
		(pad "EG60" smd circle
			(at 12.19454 22.845268 270)
			(size 0.4318 0.4318)
			(layers "F.Cu" "F.Mask" "F.Paste")
			(net "M_F_CPU0_SA_CB<2>")
		)
		(pad "EG62" smd circle
			(at 13.822426 22.845268 270)
			(size 0.4318 0.4318)
			(layers "F.Cu" "F.Mask" "F.Paste")
			(net "M_F_CPU0_SA_DQ<23>")
		)
		(pad "EG64" smd circle
			(at 15.450058 22.845268 270)
			(size 0.4318 0.4318)
			(layers "F.Cu" "F.Mask" "F.Paste")
			(net "M_F_CPU0_SA_DQS_DP<7>")
		)
		(pad "EG66" smd circle
			(at 17.07769 22.845268 270)
			(size 0.4318 0.4318)
			(layers "F.Cu" "F.Mask" "F.Paste")
			(net "M_F_CPU0_SA_DQ<18>")
		)
		(pad "EG68" smd circle
			(at 18.705576 22.845268 270)
			(size 0.4318 0.4318)
			(layers "F.Cu" "F.Mask" "F.Paste")
			(net "M_E_CPU0_SA_DQ<15>")
		)
		(pad "EG70" smd circle
			(at 20.333462 22.845268 270)
			(size 0.4318 0.4318)
			(layers "F.Cu" "F.Mask" "F.Paste")
			(net "M_E_CPU0_SA_DQS_DP<6>")
		)
		(pad "EG72" smd circle
			(at 21.961094 22.845268 270)
			(size 0.4318 0.4318)
			(layers "F.Cu" "F.Mask" "F.Paste")
			(net "M_E_CPU0_SA_DQ<10>")
		)
		(pad "EG74" smd circle
			(at 23.58898 22.845268 270)
			(size 0.4318 0.4318)
			(layers "F.Cu" "F.Mask" "F.Paste")
			(net "M_F_CPU0_SA_DQ<7>")
		)
		(pad "EG76" smd circle
			(at 25.216612 22.845268 270)
			(size 0.4318 0.4318)
			(layers "F.Cu" "F.Mask" "F.Paste")
			(net "M_F_CPU0_SA_DQS_DP<5>")
		)
		(pad "EG78" smd circle
			(at 26.844498 22.845268 270)
			(size 0.4318 0.4318)
			(layers "F.Cu" "F.Mask" "F.Paste")
			(net "M_F_CPU0_SA_DQ<3>")
		)
		(pad "EG80" smd circle
			(at 28.472384 22.845268 270)
			(size 0.4318 0.4318)
			(layers "F.Cu" "F.Mask" "F.Paste")
			(net "PVCCFA_EHV_FIVRA_CPU0")
		)
		(pad "EG82" smd circle
			(at 30.100016 22.845268 270)
			(size 0.4318 0.4318)
			(layers "F.Cu" "F.Mask" "F.Paste")
			(net "GND")
		)
		(pad "EG84" smd circle
			(at 31.727902 22.845268 270)
			(size 0.4318 0.4318)
			(layers "F.Cu" "F.Mask" "F.Paste")
			(net "GND")
		)
		(pad "EG86" smd circle
			(at 33.355534 22.845268 270)
			(size 0.4318 0.4318)
			(layers "F.Cu" "F.Mask" "F.Paste")
			(net "GND")
		)
		(pad "EG88" smd circle
			(at 34.98342 22.845268 270)
			(size 0.4318 0.4318)
			(layers "F.Cu" "F.Mask" "F.Paste")
			(net "GND")
		)
		(pad "EG90" smd oval
			(at 36.611306 22.845268 315)
			(size 0.381 0.4826)
			(drill
				(offset 0 -0.0508)
			)
			(layers "F.Cu" "F.Mask" "F.Paste")
			(net "GND")
		)
		(pad "EH2" smd oval
			(at -36.611306 23.204932 225)
			(size 0.381 0.4826)
			(drill
				(offset 0 -0.0508)
			)
			(layers "F.Cu" "F.Mask" "F.Paste")
			(net "UPI_CPU1_CPU0_P0P1_DN<0>")
		)
		(pad "EH4" smd circle
			(at -34.98342 23.204932 270)
			(size 0.4318 0.4318)
			(layers "F.Cu" "F.Mask" "F.Paste")
			(net "GND")
		)
		(pad "EH6" smd circle
			(at -33.355534 23.204932 270)
			(size 0.4318 0.4318)
			(layers "F.Cu" "F.Mask" "F.Paste")
			(net "GND")
		)
		(pad "EH8" smd circle
			(at -31.727902 23.204932 270)
			(size 0.4318 0.4318)
			(layers "F.Cu" "F.Mask" "F.Paste")
			(net "M_G_CPU0_SB_DQ<25>")
		)
		(pad "EH10" smd circle
			(at -30.100016 23.204932 270)
			(size 0.4318 0.4318)
			(layers "F.Cu" "F.Mask" "F.Paste")
			(net "P5E_CPU0_PE2_RX_DN<15>")
		)
		(pad "EH12" smd circle
			(at -28.472384 23.204932 270)
			(size 0.4318 0.4318)
			(layers "F.Cu" "F.Mask" "F.Paste")
			(net "GND")
		)
		(pad "EH14" smd circle
			(at -26.844498 23.204932 270)
			(size 0.4318 0.4318)
			(layers "F.Cu" "F.Mask" "F.Paste")
			(net "GND")
		)
		(pad "EH16" smd circle
			(at -25.216612 23.204932 270)
			(size 0.4318 0.4318)
			(layers "F.Cu" "F.Mask" "F.Paste")
			(net "GND")
		)
		(pad "EH18" smd circle
			(at -23.58898 23.204932 270)
			(size 0.4318 0.4318)
			(layers "F.Cu" "F.Mask" "F.Paste")
			(net "GND")
		)
		(pad "EH20" smd circle
			(at -21.961094 23.204932 270)
			(size 0.4318 0.4318)
			(layers "F.Cu" "F.Mask" "F.Paste")
			(net "M_F_CPU0_SB_DQ<14>")
		)
		(pad "EH22" smd circle
			(at -20.333462 23.204932 270)
			(size 0.4318 0.4318)
			(layers "F.Cu" "F.Mask" "F.Paste")
			(net "M_F_CPU0_SB_DQ<11>")
		)
		(pad "EH24" smd circle
			(at -18.705576 23.204932 270)
			(size 0.4318 0.4318)
			(layers "F.Cu" "F.Mask" "F.Paste")
			(net "GND")
		)
		(pad "EH26" smd circle
			(at -17.07769 23.204932 270)
			(size 0.4318 0.4318)
			(layers "F.Cu" "F.Mask" "F.Paste")
			(net "M_E_CPU0_SB_DQ<6>")
		)
		(pad "EH28" smd circle
			(at -15.450058 23.204932 270)
			(size 0.4318 0.4318)
			(layers "F.Cu" "F.Mask" "F.Paste")
			(net "M_E_CPU0_SB_DQ<3>")
		)
		(pad "EH30" smd circle
			(at -13.822426 23.204932 270)
			(size 0.4318 0.4318)
			(layers "F.Cu" "F.Mask" "F.Paste")
			(net "GND")
		)
		(pad "EH32" smd circle
			(at -12.19454 23.204932 270)
			(size 0.4318 0.4318)
			(layers "F.Cu" "F.Mask" "F.Paste")
			(net "M_F_CPU0_SB_CB<2>")
		)
		(pad "EH34" smd circle
			(at -10.566654 23.204932 270)
			(size 0.4318 0.4318)
			(layers "F.Cu" "F.Mask" "F.Paste")
			(net "M_F_CPU0_SB_CB<7>")
		)
		(pad "EH36" smd circle
			(at -8.939022 23.204932 270)
			(size 0.4318 0.4318)
			(layers "F.Cu" "F.Mask" "F.Paste")
			(net "GND")
		)
		(pad "EH38" smd circle
			(at -7.311136 23.204932 270)
			(size 0.4318 0.4318)
			(layers "F.Cu" "F.Mask" "F.Paste")
			(net "M_F_CPU0_SB_CS_N<0>")
		)
		(pad "EH40" smd circle
			(at -5.68325 23.204932 270)
			(size 0.4318 0.4318)
			(layers "F.Cu" "F.Mask" "F.Paste")
			(net "M_F_CPU0_SB_CA<5>")
		)
		(pad "EH42" smd circle
			(at -4.055618 23.204932 270)
			(size 0.4318 0.4318)
			(layers "F.Cu" "F.Mask" "F.Paste")
			(net "GND")
		)
		(pad "EH44" smd circle
			(at -2.427732 23.204932 270)
			(size 0.4318 0.4318)
			(layers "F.Cu" "F.Mask" "F.Paste")
			(net "M_E_CPU0_SB_CA<1>")
		)
		(pad "EH47" smd circle
			(at 1.613916 23.314914 270)
			(size 0.4318 0.4318)
			(layers "F.Cu" "F.Mask" "F.Paste")
			(net "M_H_CPU0_SA_RSP<1>")
		)
		(pad "EH49" smd circle
			(at 3.241802 23.314914 270)
			(size 0.4318 0.4318)
			(layers "F.Cu" "F.Mask" "F.Paste")
			(net "GND")
		)
		(pad "EH51" smd circle
			(at 4.869434 23.314914 270)
			(size 0.4318 0.4318)
			(layers "F.Cu" "F.Mask" "F.Paste")
			(net "M_F_CPU0_SA_CA<3>")
		)
		(pad "EH53" smd circle
			(at 6.49732 23.314914 270)
			(size 0.4318 0.4318)
			(layers "F.Cu" "F.Mask" "F.Paste")
			(net "M_F_CPU0_SA_CS_N<1>")
		)
		(pad "EH55" smd circle
			(at 8.124952 23.314914 270)
			(size 0.4318 0.4318)
			(layers "F.Cu" "F.Mask" "F.Paste")
			(net "GND")
		)
		(pad "EH57" smd circle
			(at 9.752838 23.314914 270)
			(size 0.4318 0.4318)
			(layers "F.Cu" "F.Mask" "F.Paste")
			(net "M_F_CPU0_SA_CB<6>")
		)
		(pad "EH59" smd circle
			(at 11.380724 23.314914 270)
			(size 0.4318 0.4318)
			(layers "F.Cu" "F.Mask" "F.Paste")
			(net "M_F_CPU0_SA_CB<3>")
		)
		(pad "EH61" smd circle
			(at 13.008356 23.314914 270)
			(size 0.4318 0.4318)
			(layers "F.Cu" "F.Mask" "F.Paste")
			(net "GND")
		)
		(pad "EH63" smd circle
			(at 14.635988 23.314914 270)
			(size 0.4318 0.4318)
			(layers "F.Cu" "F.Mask" "F.Paste")
			(net "M_F_CPU0_SA_DQ<22>")
		)
		(pad "EH65" smd circle
			(at 16.263874 23.314914 270)
			(size 0.4318 0.4318)
			(layers "F.Cu" "F.Mask" "F.Paste")
			(net "M_F_CPU0_SA_DQ<19>")
		)
		(pad "EH67" smd circle
			(at 17.89176 23.314914 270)
			(size 0.4318 0.4318)
			(layers "F.Cu" "F.Mask" "F.Paste")
			(net "GND")
		)
		(pad "EH69" smd circle
			(at 19.519392 23.314914 270)
			(size 0.4318 0.4318)
			(layers "F.Cu" "F.Mask" "F.Paste")
			(net "M_E_CPU0_SA_DQ<14>")
		)
	)
)
